# T6G (Grand Teton) — schematic netlist excerpt (pin names and nets, part order shuffled) for the footprints in the layout excerpt that follows; sources: Cadence DE-HDL packaged netlist, KiCad conversion of 04192023_DAF0TMB3IC0_F0TG_MB_C_brd_V02_OCP.brd

PC478_C0P0_2  Q_CAP  2.2UF 10V 10% X6S  pkg C0402  page 194 : A = PVDDCR_CPU0_P0_PVCC ; B = GND
C6722  Q_CAP_DIFFBUS  DIFF BUS_0.22UF 6.3V 20% X6S  pkg C0201  page 341 : \1\ = P5E_CPU1_P2_TX_BUF_C_DN<14> ; \2\ = P5E_CPU1_P2_TX_BUF_DN<14>
R595  Q_RES  0 5% CHIP  pkg 0201LF  page 276 : A = CLK_100M_RETIMER_CPU0_P0_R_DP ; B = CLK_100M_RETIMER_CPU0_P0_DP

(kicad_pcb
	(version 20260206)
	(generator "pcbnew")
	(generator_version "10.0")
	(general
		(thickness 1.6)
		(legacy_teardrops no)
	)
	(paper "A4")
	(title_block
		(title "04192023_DAF0TMB3IC0_F0TG_MB_C_brd_V02_OCP.brd")
		(comment 1 "Grand Teton / footprints 2138-2140 of 8354")
	)
	(layers
		(0 "F.Cu" signal "TOP")
		(4 "In1.Cu" signal "GND")
		(6 "In2.Cu" signal "IN1")
		(8 "In3.Cu" signal "GND1")
		(10 "In4.Cu" signal "IN2")
		(12 "In5.Cu" signal "GND2")
		(14 "In6.Cu" signal "IN3")
		(16 "In7.Cu" signal "GND3")
		(18 "In8.Cu" signal "VCC")
		(20 "In9.Cu" signal "VCC1")
		(22 "In10.Cu" signal "GND4")
		(24 "In11.Cu" signal "IN4")
		(26 "In12.Cu" signal "GND5")
		(28 "In13.Cu" signal "IN5")
		(30 "In14.Cu" signal "GND6")
		(32 "In15.Cu" signal "IN6")
		(34 "In16.Cu" signal "GND7")
		(2 "B.Cu" signal "BOTTOM")
		(9 "F.Adhes" user "F.Adhesive")
		(11 "B.Adhes" user "B.Adhesive")
		(13 "F.Paste" user "Package Geometry/Pastemask Top")
		(15 "B.Paste" user "Package Geometry/Pastemask Bottom")
		(5 "F.SilkS" user "Ref Des/Silkscreen Top")
		(7 "B.SilkS" user "Ref Des/Silkscreen Bottom")
		(1 "F.Mask" user "Board Geometry/Soldermask Top")
		(3 "B.Mask" user "Board Geometry/Soldermask Bottom")
		(17 "Dwgs.User" user "User.Drawings")
		(19 "Cmts.User" user "User.Comments")
		(21 "Eco1.User" user "User.Eco1")
		(23 "Eco2.User" user "User.Eco2")
		(25 "Edge.Cuts" user "Board Geometry/Outline")
		(27 "Margin" user)
		(31 "F.CrtYd" user "Package Geometry/Place Bound Top")
		(29 "B.CrtYd" user "Package Geometry/Place Bound Bottom")
		(35 "F.Fab" user "Ref Des/Assembly Top")
		(33 "B.Fab" user "Ref Des/Assembly Bottom")
	)
	(footprint ""
		(layer "F.Cu")
		(at 157.754066 -408.517344 -90)
		(property "Reference" "C6722"
			(at 0 0 270)
			(layer "F.SilkS")
			(hide yes)
			(effects
				(font
					(size 1.27 1.27)
				)
			)
		)
		(property "Value" ""
			(at 0 0 270)
			(layer "F.Fab")
			(effects
				(font
					(size 1.27 1.27)
				)
			)
		)
		(duplicate_pad_numbers_are_jumpers no)
		(fp_line
			(start -0.299974 0.150114)
			(end -0.299974 -0.150114)
			(stroke
				(width 0.1)
				(type default)
			)
			(layer "F.Fab")
		)
		(fp_line
			(start 0.299974 0.150114)
			(end -0.299974 0.150114)
			(stroke
				(width 0.1)
				(type default)
			)
			(layer "F.Fab")
		)
		(fp_line
			(start -0.299974 -0.150114)
			(end 0.299974 -0.150114)
			(stroke
				(width 0.1)
				(type default)
			)
			(layer "F.Fab")
		)
		(fp_line
			(start 0.299974 -0.150114)
			(end 0.299974 0.150114)
			(stroke
				(width 0.1)
				(type default)
			)
			(layer "F.Fab")
		)
		(pad "1" smd rect
			(at -0.2667 0 270)
			(size 0.3048 0.381)
			(layers "F.Cu" "F.Mask" "F.Paste")
			(net "P5E_CPU1_P2_TX_BUF_C_DN<14>")
		)
		(pad "2" smd rect
			(at 0.2667 0 270)
			(size 0.3048 0.381)
			(layers "F.Cu" "F.Mask" "F.Paste")
			(net "P5E_CPU1_P2_TX_BUF_DN<14>")
		)
	)
	(footprint ""
		(layer "F.Cu")
		(at 298.527724 -396.146274)
		(property "Reference" "R595"
			(at 0 0 0)
			(layer "F.SilkS")
			(hide yes)
			(effects
				(font
					(size 1.27 1.27)
				)
			)
		)
		(property "Value" ""
			(at 0 0 0)
			(layer "F.Fab")
			(effects
				(font
					(size 1.27 1.27)
				)
			)
		)
		(duplicate_pad_numbers_are_jumpers no)
		(fp_line
			(start -0.32512 -0.175006)
			(end 0.32512 -0.175006)
			(stroke
				(width 0.1)
				(type default)
			)
			(layer "F.Fab")
		)
		(fp_line
			(start -0.32512 0.175006)
			(end -0.32512 -0.175006)
			(stroke
				(width 0.1)
				(type default)
			)
			(layer "F.Fab")
		)
		(fp_line
			(start 0.32512 -0.175006)
			(end 0.32512 0.175006)
			(stroke
				(width 0.1)
				(type default)
			)
			(layer "F.Fab")
		)
		(fp_line
			(start 0.32512 0.175006)
			(end -0.32512 0.175006)
			(stroke
				(width 0.1)
				(type default)
			)
			(layer "F.Fab")
		)
		(pad "1" smd rect
			(at -0.2667 0)
			(size 0.3048 0.381)
			(layers "F.Cu" "F.Mask" "F.Paste")
			(net "CLK_100M_RETIMER_CPU0_P0_R_DP")
		)
		(pad "2" smd rect
			(at 0.2667 0 180)
			(size 0.3048 0.381)
			(layers "F.Cu" "F.Mask" "F.Paste")
			(net "CLK_100M_RETIMER_CPU0_P0_DP")
		)
	)
	(footprint ""
		(layer "F.Cu")
		(at 376.35815 -182.745634 90)
		(property "Reference" "PC478_C0P0_2"
			(at 0 0 90)
			(layer "F.SilkS")
			(hide yes)
			(effects
				(font
					(size 1.27 1.27)
				)
			)
		)
		(property "Value" ""
			(at 0 0 90)
			(layer "F.Fab")
			(effects
				(font
					(size 1.27 1.27)
				)
			)
		)
		(duplicate_pad_numbers_are_jumpers no)
		(fp_line
			(start 0.7874 -0.4064)
			(end 0.7874 0.4064)
			(stroke
				(width 0.1524)
				(type default)
			)
			(layer "F.SilkS")
		)
		(fp_line
			(start -0.7874 -0.4064)
			(end 0.7874 -0.4064)
			(stroke
				(width 0.1524)
				(type default)
			)
			(layer "F.SilkS")
		)
		(fp_line
			(start 0.7874 0.4064)
			(end -0.7874 0.4064)
			(stroke
				(width 0.1524)
				(type default)
			)
			(layer "F.SilkS")
		)
		(fp_line
			(start -0.7874 0.4064)
			(end -0.7874 -0.4064)
			(stroke
				(width 0.1524)
				(type default)
			)
			(layer "F.SilkS")
		)
		(fp_line
			(start -0.12065 -0.305054)
			(end -0.12065 -0.2794)
			(stroke
				(width 0.1)
				(type default)
			)
			(layer "F.Fab")
		)
		(fp_line
			(start -0.67945 -0.305054)
			(end -0.12065 -0.305054)
			(stroke
				(width 0.1)
				(type default)
			)
			(layer "F.Fab")
		)
		(fp_line
			(start 0.67945 -0.3048)
			(end 0.67945 0.3048)
			(stroke
				(width 0.1)
				(type default)
			)
			(layer "F.Fab")
		)
		(fp_line
			(start 0.12065 -0.3048)
			(end 0.67945 -0.3048)
			(stroke
				(width 0.1)
				(type default)
			)
			(layer "F.Fab")
		)
		(fp_line
			(start 0.12065 -0.2794)
			(end 0.12065 -0.3048)
			(stroke
				(width 0.1)
				(type default)
			)
			(layer "F.Fab")
		)
		(fp_line
			(start -0.12065 -0.2794)
			(end 0.12065 -0.2794)
			(stroke
				(width 0.1)
				(type default)
			)
			(layer "F.Fab")
		)
		(fp_line
			(start 0.120396 0.2794)
			(end -0.12065 0.2794)
			(stroke
				(width 0.1)
				(type default)
			)
			(layer "F.Fab")
		)
		(fp_line
			(start -0.12065 0.2794)
			(end -0.12065 0.3048)
			(stroke
				(width 0.1)
				(type default)
			)
			(layer "F.Fab")
		)
		(fp_line
			(start 0.67945 0.3048)
			(end 0.120396 0.3048)
			(stroke
				(width 0.1)
				(type default)
			)
			(layer "F.Fab")
		)
		(fp_line
			(start 0.120396 0.3048)
			(end 0.120396 0.2794)
			(stroke
				(width 0.1)
				(type default)
			)
			(layer "F.Fab")
		)
		(fp_line
			(start -0.12065 0.3048)
			(end -0.67945 0.3048)
			(stroke
				(width 0.1)
				(type default)
			)
			(layer "F.Fab")
		)
		(fp_line
			(start -0.67945 0.3048)
			(end -0.67945 -0.305054)
			(stroke
				(width 0.1)
				(type default)
			)
			(layer "F.Fab")
		)
		(pad "1" smd circle
			(at -0.40005 0 90)
			(size 0 0)
			(layers "F.Cu" "F.Mask" "F.Paste")
			(net "PVDDCR_CPU0_P0_PVCC")
		)
		(pad "2" smd circle
			(at 0.40005 0 90)
			(size 0 0)
			(layers "F.Cu" "F.Mask" "F.Paste")
			(net "GND")
		)
	)
)
